# SCM (Grand Teton) — schematic netlist excerpt (pin names and nets, part order shuffled) for the footprints in the layout excerpt that follows; sources: Cadence DE-HDL packaged netlist, KiCad conversion of 12092022_DA0F0TMDCD0_F0T_Management_Board_D_brd_V3_OCP.brd

R846  Q_RES  4.7K 1% EMPTY  pkg 0402LF  page 27 : A = P3V3_AUX ; B = FM_BMC_EN_DET_R
C158  Q_CAP  0.1UF 25V 10% X7R  pkg 0402  page 28 : A = P3V3_AUX ; B = GND

(kicad_pcb
	(version 20260206)
	(generator "pcbnew")
	(generator_version "10.0")
	(general
		(thickness 1.6)
		(legacy_teardrops no)
	)
	(paper "A4")
	(title_block
		(title "12092022_DA0F0TMDCD0_F0T_Management_Board_D_brd_V3_OCP.brd")
		(comment 1 "Grand Teton / footprints 901-902 of 1440")
	)
	(layers
		(0 "F.Cu" signal "TOP")
		(4 "In1.Cu" signal "GND")
		(6 "In2.Cu" signal "IN1")
		(8 "In3.Cu" signal "GND1")
		(10 "In4.Cu" signal "IN2")
		(12 "In5.Cu" signal "VCC")
		(14 "In6.Cu" signal "VCC1")
		(16 "In7.Cu" signal "IN3")
		(18 "In8.Cu" signal "GND2")
		(20 "In9.Cu" signal "IN4")
		(22 "In10.Cu" signal "GND3")
		(2 "B.Cu" signal "BOTTOM")
		(9 "F.Adhes" user "F.Adhesive")
		(11 "B.Adhes" user "B.Adhesive")
		(13 "F.Paste" user "Package Geometry/Pastemask Top")
		(15 "B.Paste" user "Package Geometry/Pastemask Bottom")
		(5 "F.SilkS" user "Ref Des/Silkscreen Top")
		(7 "B.SilkS" user "Ref Des/Silkscreen Bottom")
		(1 "F.Mask" user "Board Geometry/Soldermask Top")
		(3 "B.Mask" user "Board Geometry/Soldermask Bottom")
		(17 "Dwgs.User" user "User.Drawings")
		(19 "Cmts.User" user "User.Comments")
		(21 "Eco1.User" user "User.Eco1")
		(23 "Eco2.User" user "User.Eco2")
		(25 "Edge.Cuts" user "Board Geometry/Outline")
		(27 "Margin" user)
		(31 "F.CrtYd" user "Package Geometry/Place Bound Top")
		(29 "B.CrtYd" user "Package Geometry/Place Bound Bottom")
		(35 "F.Fab" user "Ref Des/Assembly Top")
		(33 "B.Fab" user "Ref Des/Assembly Bottom")
	)
	(footprint ""
		(layer "B.Cu")
		(at 17.653 -60.325 90)
		(property "Reference" "C158"
			(at 0 0 90)
			(layer "B.SilkS")
			(hide yes)
			(effects
				(font
					(size 1.27 1.27)
				)
				(justify mirror)
			)
		)
		(property "Value" ""
			(at 0 0 90)
			(layer "B.Fab")
			(effects
				(font
					(size 1.27 1.27)
				)
				(justify mirror)
			)
		)
		(duplicate_pad_numbers_are_jumpers no)
		(fp_line
			(start 0.7874 -0.4064)
			(end -0.7874 -0.4064)
			(stroke
				(width 0.1524)
				(type default)
			)
			(layer "B.SilkS")
		)
		(fp_line
			(start -0.7874 -0.4064)
			(end -0.7874 0.4064)
			(stroke
				(width 0.1524)
				(type default)
			)
			(layer "B.SilkS")
		)
		(fp_line
			(start 0.7874 0.4064)
			(end 0.7874 -0.4064)
			(stroke
				(width 0.1524)
				(type default)
			)
			(layer "B.SilkS")
		)
		(fp_line
			(start -0.7874 0.4064)
			(end 0.7874 0.4064)
			(stroke
				(width 0.1524)
				(type default)
			)
			(layer "B.SilkS")
		)
		(fp_line
			(start 0.67945 -0.305054)
			(end 0.12065 -0.305054)
			(stroke
				(width 0.1)
				(type default)
			)
			(layer "B.Fab")
		)
		(fp_line
			(start 0.12065 -0.305054)
			(end 0.12065 -0.2794)
			(stroke
				(width 0.1)
				(type default)
			)
			(layer "B.Fab")
		)
		(fp_line
			(start -0.12065 -0.3048)
			(end -0.67945 -0.3048)
			(stroke
				(width 0.1)
				(type default)
			)
			(layer "B.Fab")
		)
		(fp_line
			(start -0.67945 -0.3048)
			(end -0.67945 0.3048)
			(stroke
				(width 0.1)
				(type default)
			)
			(layer "B.Fab")
		)
		(fp_line
			(start 0.12065 -0.2794)
			(end -0.12065 -0.2794)
			(stroke
				(width 0.1)
				(type default)
			)
			(layer "B.Fab")
		)
		(fp_line
			(start -0.12065 -0.2794)
			(end -0.12065 -0.3048)
			(stroke
				(width 0.1)
				(type default)
			)
			(layer "B.Fab")
		)
		(fp_line
			(start 0.12065 0.2794)
			(end 0.12065 0.3048)
			(stroke
				(width 0.1)
				(type default)
			)
			(layer "B.Fab")
		)
		(fp_line
			(start -0.120396 0.2794)
			(end 0.12065 0.2794)
			(stroke
				(width 0.1)
				(type default)
			)
			(layer "B.Fab")
		)
		(fp_line
			(start 0.67945 0.3048)
			(end 0.67945 -0.305054)
			(stroke
				(width 0.1)
				(type default)
			)
			(layer "B.Fab")
		)
		(fp_line
			(start 0.12065 0.3048)
			(end 0.67945 0.3048)
			(stroke
				(width 0.1)
				(type default)
			)
			(layer "B.Fab")
		)
		(fp_line
			(start -0.120396 0.3048)
			(end -0.120396 0.2794)
			(stroke
				(width 0.1)
				(type default)
			)
			(layer "B.Fab")
		)
		(fp_line
			(start -0.67945 0.3048)
			(end -0.120396 0.3048)
			(stroke
				(width 0.1)
				(type default)
			)
			(layer "B.Fab")
		)
		(pad "1" smd circle
			(at 0.40005 0 270)
			(size 0 0)
			(layers "B.Cu" "B.Mask" "B.Paste")
			(net "P3V3_AUX")
		)
		(pad "2" smd circle
			(at -0.40005 0 270)
			(size 0 0)
			(layers "B.Cu" "B.Mask" "B.Paste")
			(net "GND")
		)
	)
	(footprint ""
		(layer "B.Cu")
		(at 49.461166 -62.116462 90)
		(property "Reference" "R846"
			(at 0 0 90)
			(layer "B.SilkS")
			(hide yes)
			(effects
				(font
					(size 1.27 1.27)
				)
				(justify mirror)
			)
		)
		(property "Value" ""
			(at 0 0 90)
			(layer "B.Fab")
			(effects
				(font
					(size 1.27 1.27)
				)
				(justify mirror)
			)
		)
		(duplicate_pad_numbers_are_jumpers no)
		(fp_line
			(start 0.7874 -0.4064)
			(end -0.7874 -0.4064)
			(stroke
				(width 0.1524)
				(type default)
			)
			(layer "B.SilkS")
		)
		(fp_line
			(start -0.7874 -0.4064)
			(end -0.7874 0.4064)
			(stroke
				(width 0.1524)
				(type default)
			)
			(layer "B.SilkS")
		)
		(fp_line
			(start 0.7874 0.4064)
			(end 0.7874 -0.4064)
			(stroke
				(width 0.1524)
				(type default)
			)
			(layer "B.SilkS")
		)
		(fp_line
			(start -0.7874 0.4064)
			(end 0.7874 0.4064)
			(stroke
				(width 0.1524)
				(type default)
			)
			(layer "B.SilkS")
		)
		(fp_line
			(start 0.67945 -0.305054)
			(end 0.12065 -0.305054)
			(stroke
				(width 0.1)
				(type default)
			)
			(layer "B.Fab")
		)
		(fp_line
			(start 0.12065 -0.305054)
			(end 0.12065 -0.2794)
			(stroke
				(width 0.1)
				(type default)
			)
			(layer "B.Fab")
		)
		(fp_line
			(start -0.12065 -0.3048)
			(end -0.67945 -0.3048)
			(stroke
				(width 0.1)
				(type default)
			)
			(layer "B.Fab")
		)
		(fp_line
			(start -0.67945 -0.3048)
			(end -0.67945 0.3048)
			(stroke
				(width 0.1)
				(type default)
			)
			(layer "B.Fab")
		)
		(fp_line
			(start 0.12065 -0.2794)
			(end -0.12065 -0.2794)
			(stroke
				(width 0.1)
				(type default)
			)
			(layer "B.Fab")
		)
		(fp_line
			(start -0.12065 -0.2794)
			(end -0.12065 -0.3048)
			(stroke
				(width 0.1)
				(type default)
			)
			(layer "B.Fab")
		)
		(fp_line
			(start 0.12065 0.2794)
			(end 0.12065 0.3048)
			(stroke
				(width 0.1)
				(type default)
			)
			(layer "B.Fab")
		)
		(fp_line
			(start -0.120396 0.2794)
			(end 0.12065 0.2794)
			(stroke
				(width 0.1)
				(type default)
			)
			(layer "B.Fab")
		)
		(fp_line
			(start 0.67945 0.3048)
			(end 0.67945 -0.305054)
			(stroke
				(width 0.1)
				(type default)
			)
			(layer "B.Fab")
		)
		(fp_line
			(start 0.12065 0.3048)
			(end 0.67945 0.3048)
			(stroke
				(width 0.1)
				(type default)
			)
			(layer "B.Fab")
		)
		(fp_line
			(start -0.120396 0.3048)
			(end -0.120396 0.2794)
			(stroke
				(width 0.1)
				(type default)
			)
			(layer "B.Fab")
		)
		(fp_line
			(start -0.67945 0.3048)
			(end -0.120396 0.3048)
			(stroke
				(width 0.1)
				(type default)
			)
			(layer "B.Fab")
		)
		(pad "1" smd circle
			(at 0.40005 0 270)
			(size 0 0)
			(layers "B.Cu" "B.Mask" "B.Paste")
			(net "P3V3_AUX")
		)
		(pad "2" smd circle
			(at -0.40005 0 270)
			(size 0 0)
			(layers "B.Cu" "B.Mask" "B.Paste")
			(net "FM_BMC_EN_DET_R")
		)
	)
)
